(kicad_pcb
	(version 20260206)
	(generator "pcbnew")
	(generator_version "10.0")
	(general
		(thickness 1.6)
		(legacy_teardrops no)
	)
	(paper "A4")
	(title_block
		(title "v1-pdb — T6M_PDB_D_0927_0900.brd")
		(comment 1 "Open CloudServer (Microsoft) / footprint 271 of 321 (J25), pads 79-156 of 166")
	)
	(layers
		(0 "F.Cu" signal "TOP")
		(4 "In1.Cu" signal "GND")
		(6 "In2.Cu" signal "IN1")
		(8 "In3.Cu" signal "VCC")
		(10 "In4.Cu" signal "VCC1")
		(12 "In5.Cu" signal "IN2")
		(14 "In6.Cu" signal "GND1")
		(2 "B.Cu" signal "BOTTOM")
		(9 "F.Adhes" user "F.Adhesive")
		(11 "B.Adhes" user "B.Adhesive")
		(13 "F.Paste" user "Package Geometry/Pastemask Top")
		(15 "B.Paste" user "Package Geometry/Pastemask Bottom")
		(5 "F.SilkS" user "Ref Des/Silkscreen Top")
		(7 "B.SilkS" user "Ref Des/Silkscreen Bottom")
		(1 "F.Mask" user "Board Geometry/Soldermask Top")
		(3 "B.Mask" user "Board Geometry/Soldermask Bottom")
		(17 "Dwgs.User" user "User.Drawings")
		(19 "Cmts.User" user "User.Comments")
		(21 "Eco1.User" user "User.Eco1")
		(23 "Eco2.User" user "User.Eco2")
		(25 "Edge.Cuts" user "Board Geometry/Outline")
		(27 "Margin" user)
		(31 "F.CrtYd" user "Package Geometry/Place Bound Top")
		(29 "B.CrtYd" user "Package Geometry/Place Bound Bottom")
		(35 "F.Fab" user "Ref Des/Assembly Top")
		(33 "B.Fab" user "Ref Des/Assembly Bottom")
	)
	(footprint ""
		(layer "F.Cu")
		(at 6.449822 -352.669856)
		(property "Reference" "J25"
			(at 6.653784 1.81356 90)
			(unlocked yes)
			(layer "F.SilkS")
			(effects
				(font
					(size 0.7874 0.5842)
					(thickness 0.1524)
				)
				(justify left)
			)
		)
		(property "Value" ""
			(at 0 0 0)
			(layer "F.Fab")
			(effects
				(font
					(size 1.27 1.27)
				)
			)
		)
		(duplicate_pad_numbers_are_jumpers no)
		(pad "A77" thru_hole circle
			(at 0 78.000098 270)
			(size 1.016 1.016)
			(drill 0.7112)
			(layers "*.Cu" "*.Mask")
			(remove_unused_layers no)
			(net "T7_BLAD4_RXD")
			(clearance 0.1016)
			(thermal_gap 0.1016)
		)
		(pad "A78" thru_hole circle
			(at 1.999996 79.000096 270)
			(size 1.016 1.016)
			(drill 0.7112)
			(layers "*.Cu" "*.Mask")
			(remove_unused_layers no)
			(net "T7_BLAD4_TXD")
			(clearance 0.1016)
			(thermal_gap 0.1016)
		)
		(pad "A79" thru_hole circle
			(at 0 80.000094 270)
			(size 1.016 1.016)
			(drill 0.7112)
			(layers "*.Cu" "*.Mask")
			(remove_unused_layers no)
			(net "GND")
			(clearance 0.1016)
			(thermal_gap 0.1016)
		)
		(pad "A80" thru_hole circle
			(at 1.999996 81.000092 270)
			(size 1.016 1.016)
			(drill 0.7112)
			(layers "*.Cu" "*.Mask")
			(remove_unused_layers no)
			(net "PSU_ALERT_N")
			(clearance 0.1016)
			(thermal_gap 0.1016)
		)
		(pad "A81" thru_hole circle
			(at 0 82.00009 270)
			(size 1.016 1.016)
			(drill 0.7112)
			(layers "*.Cu" "*.Mask")
			(remove_unused_layers no)
			(net "T5_BLAD1_EN")
			(clearance 0.1016)
			(thermal_gap 0.1016)
		)
		(pad "A82" thru_hole circle
			(at 1.999996 83.000088 270)
			(size 1.016 1.016)
			(drill 0.7112)
			(layers "*.Cu" "*.Mask")
			(remove_unused_layers no)
			(net "T5_BLAD2_EN")
			(clearance 0.1016)
			(thermal_gap 0.1016)
		)
		(pad "B1" thru_hole circle
			(at -2.499868 0 270)
			(size 1.016 1.016)
			(drill 0.7112)
			(layers "*.Cu" "*.Mask")
			(remove_unused_layers no)
			(net "GND")
			(clearance 0.1016)
			(thermal_gap 0.1016)
		)
		(pad "B2" thru_hole circle
			(at -4.499864 0.999998 270)
			(size 1.016 1.016)
			(drill 0.7112)
			(layers "*.Cu" "*.Mask")
			(remove_unused_layers no)
			(net "LAN2_P1_P")
			(clearance 0.1016)
			(thermal_gap 0.1016)
		)
		(pad "B3" thru_hole circle
			(at -2.499868 1.999996 270)
			(size 1.016 1.016)
			(drill 0.7112)
			(layers "*.Cu" "*.Mask")
			(remove_unused_layers no)
			(net "LAN2_P1_N")
			(clearance 0.1016)
			(thermal_gap 0.1016)
		)
		(pad "B4" thru_hole circle
			(at -4.499864 2.999994 270)
			(size 1.016 1.016)
			(drill 0.7112)
			(layers "*.Cu" "*.Mask")
			(remove_unused_layers no)
			(net "GND")
			(clearance 0.1016)
			(thermal_gap 0.1016)
		)
		(pad "B5" thru_hole circle
			(at -2.499868 3.999992 270)
			(size 1.016 1.016)
			(drill 0.7112)
			(layers "*.Cu" "*.Mask")
			(remove_unused_layers no)
			(net "LAN2_P2_P")
			(clearance 0.1016)
			(thermal_gap 0.1016)
		)
		(pad "B6" thru_hole circle
			(at -4.499864 4.99999 270)
			(size 1.016 1.016)
			(drill 0.7112)
			(layers "*.Cu" "*.Mask")
			(remove_unused_layers no)
			(net "LAN2_P2_N")
			(clearance 0.1016)
			(thermal_gap 0.1016)
		)
		(pad "B7" thru_hole circle
			(at -2.499868 5.999988 270)
			(size 1.016 1.016)
			(drill 0.7112)
			(layers "*.Cu" "*.Mask")
			(remove_unused_layers no)
			(net "GND")
			(clearance 0.1016)
			(thermal_gap 0.1016)
		)
		(pad "B8" thru_hole circle
			(at -4.499864 6.999986 270)
			(size 1.016 1.016)
			(drill 0.7112)
			(layers "*.Cu" "*.Mask")
			(remove_unused_layers no)
			(net "GND")
			(clearance 0.1016)
			(thermal_gap 0.1016)
		)
		(pad "B9" thru_hole circle
			(at -2.499868 7.999984 270)
			(size 1.016 1.016)
			(drill 0.7112)
			(layers "*.Cu" "*.Mask")
			(remove_unused_layers no)
			(net "GND")
			(clearance 0.1016)
			(thermal_gap 0.1016)
		)
		(pad "B10" thru_hole circle
			(at -4.499864 8.999982 270)
			(size 1.016 1.016)
			(drill 0.7112)
			(layers "*.Cu" "*.Mask")
			(remove_unused_layers no)
			(net "I2C_PDB_SCL")
			(clearance 0.1016)
			(thermal_gap 0.1016)
		)
		(pad "B11" thru_hole circle
			(at -2.499868 9.99998 270)
			(size 1.016 1.016)
			(drill 0.7112)
			(layers "*.Cu" "*.Mask")
			(remove_unused_layers no)
			(net "I2C_PDB_SDA")
			(clearance 0.1016)
			(thermal_gap 0.1016)
		)
		(pad "B12" thru_hole circle
			(at -4.499864 12.999974 270)
			(size 1.016 1.016)
			(drill 0.7112)
			(layers "*.Cu" "*.Mask")
			(remove_unused_layers no)
			(net "P3V3")
			(clearance 0.1016)
			(thermal_gap 0.1016)
		)
		(pad "B13" thru_hole circle
			(at -2.499868 13.999972 270)
			(size 1.016 1.016)
			(drill 0.7112)
			(layers "*.Cu" "*.Mask")
			(remove_unused_layers no)
			(net "GND3")
			(clearance 0.1016)
			(thermal_gap 0.1016)
		)
		(pad "B14" thru_hole circle
			(at -4.499864 14.99997 270)
			(size 1.016 1.016)
			(drill 0.7112)
			(layers "*.Cu" "*.Mask")
			(remove_unused_layers no)
			(net "Net_420")
			(clearance 0.1016)
			(thermal_gap 0.1016)
		)
		(pad "B15" thru_hole circle
			(at -2.499868 15.999968 270)
			(size 1.016 1.016)
			(drill 0.7112)
			(layers "*.Cu" "*.Mask")
			(remove_unused_layers no)
			(net "Net_419")
			(clearance 0.1016)
			(thermal_gap 0.1016)
		)
		(pad "B16" thru_hole circle
			(at -4.499864 16.999966 270)
			(size 1.016 1.016)
			(drill 0.7112)
			(layers "*.Cu" "*.Mask")
			(remove_unused_layers no)
			(net "GND4")
			(clearance 0.1016)
			(thermal_gap 0.1016)
		)
		(pad "B17" thru_hole circle
			(at -2.499868 17.999964 270)
			(size 1.016 1.016)
			(drill 0.7112)
			(layers "*.Cu" "*.Mask")
			(remove_unused_layers no)
			(net "Net_418")
			(clearance 0.1016)
			(thermal_gap 0.1016)
		)
		(pad "B18" thru_hole circle
			(at -4.499864 18.999962 270)
			(size 1.016 1.016)
			(drill 0.7112)
			(layers "*.Cu" "*.Mask")
			(remove_unused_layers no)
			(net "GND")
			(clearance 0.1016)
			(thermal_gap 0.1016)
		)
		(pad "B19" thru_hole circle
			(at -2.499868 19.99996 270)
			(size 1.016 1.016)
			(drill 0.7112)
			(layers "*.Cu" "*.Mask")
			(remove_unused_layers no)
			(net "UART_RTS_RP5_L_N")
			(clearance 0.1016)
			(thermal_gap 0.1016)
		)
		(pad "B20" thru_hole circle
			(at -4.499864 20.999958 270)
			(size 1.016 1.016)
			(drill 0.7112)
			(layers "*.Cu" "*.Mask")
			(remove_unused_layers no)
			(net "UART_DSR_RP5_L")
			(clearance 0.1016)
			(thermal_gap 0.1016)
		)
		(pad "B21" thru_hole circle
			(at -2.499868 21.999956 270)
			(size 1.016 1.016)
			(drill 0.7112)
			(layers "*.Cu" "*.Mask")
			(remove_unused_layers no)
			(net "UART_RX_RP5_L")
			(clearance 0.1016)
			(thermal_gap 0.1016)
		)
		(pad "B22" thru_hole circle
			(at -4.499864 22.999954 270)
			(size 1.016 1.016)
			(drill 0.7112)
			(layers "*.Cu" "*.Mask")
			(remove_unused_layers no)
			(net "UART_TX_RP5_L")
			(clearance 0.1016)
			(thermal_gap 0.1016)
		)
		(pad "B23" thru_hole circle
			(at -2.499868 23.999952 270)
			(size 1.016 1.016)
			(drill 0.7112)
			(layers "*.Cu" "*.Mask")
			(remove_unused_layers no)
			(net "UART_DTR_RP5_L_N")
			(clearance 0.1016)
			(thermal_gap 0.1016)
		)
		(pad "B24" thru_hole circle
			(at -4.499864 24.99995 270)
			(size 1.016 1.016)
			(drill 0.7112)
			(layers "*.Cu" "*.Mask")
			(remove_unused_layers no)
			(net "UART_CTS_RP5_L_N")
			(clearance 0.1016)
			(thermal_gap 0.1016)
		)
		(pad "B25" thru_hole circle
			(at -2.499868 25.999948 270)
			(size 1.016 1.016)
			(drill 0.7112)
			(layers "*.Cu" "*.Mask")
			(remove_unused_layers no)
			(net "UART_RI_RP5_L_N")
			(clearance 0.1016)
			(thermal_gap 0.1016)
		)
		(pad "B26" thru_hole circle
			(at -4.499864 26.999946 270)
			(size 1.016 1.016)
			(drill 0.7112)
			(layers "*.Cu" "*.Mask")
			(remove_unused_layers no)
			(net "GND")
			(clearance 0.1016)
			(thermal_gap 0.1016)
		)
		(pad "B27" thru_hole circle
			(at -2.499868 27.999944 270)
			(size 1.016 1.016)
			(drill 0.7112)
			(layers "*.Cu" "*.Mask")
			(remove_unused_layers no)
			(net "FAN1_TACH")
			(clearance 0.1016)
			(thermal_gap 0.1016)
		)
		(pad "B28" thru_hole circle
			(at -4.499864 28.999942 270)
			(size 1.016 1.016)
			(drill 0.7112)
			(layers "*.Cu" "*.Mask")
			(remove_unused_layers no)
			(net "FAN2_TACH")
			(clearance 0.1016)
			(thermal_gap 0.1016)
		)
		(pad "B29" thru_hole circle
			(at -2.499868 29.99994 270)
			(size 1.016 1.016)
			(drill 0.7112)
			(layers "*.Cu" "*.Mask")
			(remove_unused_layers no)
			(net "FAN3_TACH")
			(clearance 0.1016)
			(thermal_gap 0.1016)
		)
		(pad "B30" thru_hole circle
			(at -4.499864 30.999938 270)
			(size 1.016 1.016)
			(drill 0.7112)
			(layers "*.Cu" "*.Mask")
			(remove_unused_layers no)
			(net "GND")
			(clearance 0.1016)
			(thermal_gap 0.1016)
		)
		(pad "B31" thru_hole circle
			(at -2.499868 31.999936 270)
			(size 1.016 1.016)
			(drill 0.7112)
			(layers "*.Cu" "*.Mask")
			(remove_unused_layers no)
			(net "T12_BLAD1_EN")
			(clearance 0.1016)
			(thermal_gap 0.1016)
		)
		(pad "B32" thru_hole circle
			(at -4.499864 32.999934 270)
			(size 1.016 1.016)
			(drill 0.7112)
			(layers "*.Cu" "*.Mask")
			(remove_unused_layers no)
			(net "T12_BLAD2_EN")
			(clearance 0.1016)
			(thermal_gap 0.1016)
		)
		(pad "B33" thru_hole circle
			(at -2.499868 33.999932 270)
			(size 1.016 1.016)
			(drill 0.7112)
			(layers "*.Cu" "*.Mask")
			(remove_unused_layers no)
			(net "T12_BLAD3_EN")
			(clearance 0.1016)
			(thermal_gap 0.1016)
		)
		(pad "B34" thru_hole circle
			(at -4.499864 34.99993 270)
			(size 1.016 1.016)
			(drill 0.7112)
			(layers "*.Cu" "*.Mask")
			(remove_unused_layers no)
			(net "T12_BLAD4_EN")
			(clearance 0.1016)
			(thermal_gap 0.1016)
		)
		(pad "B35" thru_hole circle
			(at -2.499868 35.999928 270)
			(size 1.016 1.016)
			(drill 0.7112)
			(layers "*.Cu" "*.Mask")
			(remove_unused_layers no)
			(net "GND")
			(clearance 0.1016)
			(thermal_gap 0.1016)
		)
		(pad "B36" thru_hole circle
			(at -4.499864 36.999926 270)
			(size 1.016 1.016)
			(drill 0.7112)
			(layers "*.Cu" "*.Mask")
			(remove_unused_layers no)
			(net "T12_BLAD1_RXD")
			(clearance 0.1016)
			(thermal_gap 0.1016)
		)
		(pad "B37" thru_hole circle
			(at -2.499868 37.999924 270)
			(size 1.016 1.016)
			(drill 0.7112)
			(layers "*.Cu" "*.Mask")
			(remove_unused_layers no)
			(net "T12_BLAD1_TXD")
			(clearance 0.1016)
			(thermal_gap 0.1016)
		)
		(pad "B38" thru_hole circle
			(at -4.499864 38.999922 270)
			(size 1.016 1.016)
			(drill 0.7112)
			(layers "*.Cu" "*.Mask")
			(remove_unused_layers no)
			(net "T12_BLAD2_RXD")
			(clearance 0.1016)
			(thermal_gap 0.1016)
		)
		(pad "B39" thru_hole circle
			(at -2.499868 39.99992 270)
			(size 1.016 1.016)
			(drill 0.7112)
			(layers "*.Cu" "*.Mask")
			(remove_unused_layers no)
			(net "T12_BLAD2_TXD")
			(clearance 0.1016)
			(thermal_gap 0.1016)
		)
		(pad "B40" thru_hole circle
			(at -4.499864 40.999918 270)
			(size 1.016 1.016)
			(drill 0.7112)
			(layers "*.Cu" "*.Mask")
			(remove_unused_layers no)
			(net "GND")
			(clearance 0.1016)
			(thermal_gap 0.1016)
		)
		(pad "B41" thru_hole circle
			(at -2.499868 41.999916 270)
			(size 1.016 1.016)
			(drill 0.7112)
			(layers "*.Cu" "*.Mask")
			(remove_unused_layers no)
			(net "T12_BLAD3_RXD")
			(clearance 0.1016)
			(thermal_gap 0.1016)
		)
		(pad "B42" thru_hole circle
			(at -4.499864 42.999914 270)
			(size 1.016 1.016)
			(drill 0.7112)
			(layers "*.Cu" "*.Mask")
			(remove_unused_layers no)
			(net "T12_BLAD3_TXD")
			(clearance 0.1016)
			(thermal_gap 0.1016)
		)
		(pad "B43" thru_hole circle
			(at -2.499868 43.999912 270)
			(size 1.016 1.016)
			(drill 0.7112)
			(layers "*.Cu" "*.Mask")
			(remove_unused_layers no)
			(net "T12_BLAD4_RXD")
			(clearance 0.1016)
			(thermal_gap 0.1016)
		)
		(pad "B44" thru_hole circle
			(at -4.499864 44.99991 270)
			(size 1.016 1.016)
			(drill 0.7112)
			(layers "*.Cu" "*.Mask")
			(remove_unused_layers no)
			(net "T12_BLAD4_TXD")
			(clearance 0.1016)
			(thermal_gap 0.1016)
		)
		(pad "B45" thru_hole circle
			(at -2.499868 45.999908 270)
			(size 1.016 1.016)
			(drill 0.7112)
			(layers "*.Cu" "*.Mask")
			(remove_unused_layers no)
			(net "GND")
			(clearance 0.1016)
			(thermal_gap 0.1016)
		)
		(pad "B46" thru_hole circle
			(at -4.499864 46.999906 270)
			(size 1.016 1.016)
			(drill 0.7112)
			(layers "*.Cu" "*.Mask")
			(remove_unused_layers no)
			(net "T10_BLAD1_EN")
			(clearance 0.1016)
			(thermal_gap 0.1016)
		)
		(pad "B47" thru_hole circle
			(at -2.499868 47.999904 270)
			(size 1.016 1.016)
			(drill 0.7112)
			(layers "*.Cu" "*.Mask")
			(remove_unused_layers no)
			(net "T10_BLAD2_EN")
			(clearance 0.1016)
			(thermal_gap 0.1016)
		)
		(pad "B48" thru_hole circle
			(at -4.499864 48.999902 270)
			(size 1.016 1.016)
			(drill 0.7112)
			(layers "*.Cu" "*.Mask")
			(remove_unused_layers no)
			(net "T10_BLAD3_EN")
			(clearance 0.1016)
			(thermal_gap 0.1016)
		)
		(pad "B49" thru_hole circle
			(at -2.499868 49.9999 270)
			(size 1.016 1.016)
			(drill 0.7112)
			(layers "*.Cu" "*.Mask")
			(remove_unused_layers no)
			(net "T10_BLAD4_EN")
			(clearance 0.1016)
			(thermal_gap 0.1016)
		)
		(pad "B50" thru_hole circle
			(at -4.499864 50.999898 270)
			(size 1.016 1.016)
			(drill 0.7112)
			(layers "*.Cu" "*.Mask")
			(remove_unused_layers no)
			(net "GND")
			(clearance 0.1016)
			(thermal_gap 0.1016)
		)
		(pad "B51" thru_hole circle
			(at -2.499868 51.999896 270)
			(size 1.016 1.016)
			(drill 0.7112)
			(layers "*.Cu" "*.Mask")
			(remove_unused_layers no)
			(net "T10_BLAD1_RXD")
			(clearance 0.1016)
			(thermal_gap 0.1016)
		)
		(pad "B52" thru_hole circle
			(at -4.499864 52.999894 270)
			(size 1.016 1.016)
			(drill 0.7112)
			(layers "*.Cu" "*.Mask")
			(remove_unused_layers no)
			(net "T10_BLAD1_TXD")
			(clearance 0.1016)
			(thermal_gap 0.1016)
		)
		(pad "B53" thru_hole circle
			(at -2.499868 53.999892 270)
			(size 1.016 1.016)
			(drill 0.7112)
			(layers "*.Cu" "*.Mask")
			(remove_unused_layers no)
			(net "T10_BLAD2_RXD")
			(clearance 0.1016)
			(thermal_gap 0.1016)
		)
		(pad "B54" thru_hole circle
			(at -4.499864 54.99989 270)
			(size 1.016 1.016)
			(drill 0.7112)
			(layers "*.Cu" "*.Mask")
			(remove_unused_layers no)
			(net "T10_BLAD2_TXD")
			(clearance 0.1016)
			(thermal_gap 0.1016)
		)
		(pad "B55" thru_hole circle
			(at -2.499868 55.999888 270)
			(size 1.016 1.016)
			(drill 0.7112)
			(layers "*.Cu" "*.Mask")
			(remove_unused_layers no)
			(net "GND")
			(clearance 0.1016)
			(thermal_gap 0.1016)
		)
		(pad "B56" thru_hole circle
			(at -4.499864 56.999886 270)
			(size 1.016 1.016)
			(drill 0.7112)
			(layers "*.Cu" "*.Mask")
			(remove_unused_layers no)
			(net "T10_BLAD3_RXD")
			(clearance 0.1016)
			(thermal_gap 0.1016)
		)
		(pad "B57" thru_hole circle
			(at -2.499868 57.999884 270)
			(size 1.016 1.016)
			(drill 0.7112)
			(layers "*.Cu" "*.Mask")
			(remove_unused_layers no)
			(net "T10_BLAD3_TXD")
			(clearance 0.1016)
			(thermal_gap 0.1016)
		)
		(pad "B58" thru_hole circle
			(at -4.499864 59.000136 270)
			(size 1.016 1.016)
			(drill 0.7112)
			(layers "*.Cu" "*.Mask")
			(remove_unused_layers no)
			(net "T10_BLAD4_RXD")
			(clearance 0.1016)
			(thermal_gap 0.1016)
		)
		(pad "B59" thru_hole circle
			(at -2.499868 59.99988 270)
			(size 1.016 1.016)
			(drill 0.7112)
			(layers "*.Cu" "*.Mask")
			(remove_unused_layers no)
			(net "T10_BLAD4_TXD")
			(clearance 0.1016)
			(thermal_gap 0.1016)
		)
		(pad "B60" thru_hole circle
			(at -4.499864 61.000132 270)
			(size 1.016 1.016)
			(drill 0.7112)
			(layers "*.Cu" "*.Mask")
			(remove_unused_layers no)
			(net "GND")
			(clearance 0.1016)
			(thermal_gap 0.1016)
		)
		(pad "B61" thru_hole circle
			(at -2.499868 61.999876 270)
			(size 1.016 1.016)
			(drill 0.7112)
			(layers "*.Cu" "*.Mask")
			(remove_unused_layers no)
			(net "T8_BLAD1_EN")
			(clearance 0.1016)
			(thermal_gap 0.1016)
		)
		(pad "B62" thru_hole circle
			(at -4.499864 63.000128 270)
			(size 1.016 1.016)
			(drill 0.7112)
			(layers "*.Cu" "*.Mask")
			(remove_unused_layers no)
			(net "T8_BLAD2_EN")
			(clearance 0.1016)
			(thermal_gap 0.1016)
		)
		(pad "B63" thru_hole circle
			(at -2.499868 63.999872 270)
			(size 1.016 1.016)
			(drill 0.7112)
			(layers "*.Cu" "*.Mask")
			(remove_unused_layers no)
			(net "T8_BLAD3_EN")
			(clearance 0.1016)
			(thermal_gap 0.1016)
		)
		(pad "B64" thru_hole circle
			(at -4.499864 65.000124 270)
			(size 1.016 1.016)
			(drill 0.7112)
			(layers "*.Cu" "*.Mask")
			(remove_unused_layers no)
			(net "T8_BLAD4_EN")
			(clearance 0.1016)
			(thermal_gap 0.1016)
		)
		(pad "B65" thru_hole circle
			(at -2.499868 65.999868 270)
			(size 1.016 1.016)
			(drill 0.7112)
			(layers "*.Cu" "*.Mask")
			(remove_unused_layers no)
			(net "GND")
			(clearance 0.1016)
			(thermal_gap 0.1016)
		)
		(pad "B66" thru_hole circle
			(at -4.499864 67.00012 270)
			(size 1.016 1.016)
			(drill 0.7112)
			(layers "*.Cu" "*.Mask")
			(remove_unused_layers no)
			(net "T8_BLAD1_RXD")
			(clearance 0.1016)
			(thermal_gap 0.1016)
		)
		(pad "B67" thru_hole circle
			(at -2.499868 67.999864 270)
			(size 1.016 1.016)
			(drill 0.7112)
			(layers "*.Cu" "*.Mask")
			(remove_unused_layers no)
			(net "T8_BLAD1_TXD")
			(clearance 0.1016)
			(thermal_gap 0.1016)
		)
		(pad "B68" thru_hole circle
			(at -4.499864 69.000116 270)
			(size 1.016 1.016)
			(drill 0.7112)
			(layers "*.Cu" "*.Mask")
			(remove_unused_layers no)
			(net "T8_BLAD2_RXD")
			(clearance 0.1016)
			(thermal_gap 0.1016)
		)
		(pad "B69" thru_hole circle
			(at -2.499868 70.000114 270)
			(size 1.016 1.016)
			(drill 0.7112)
			(layers "*.Cu" "*.Mask")
			(remove_unused_layers no)
			(net "T8_BLAD2_TXD")
			(clearance 0.1016)
			(thermal_gap 0.1016)
		)
		(pad "B70" thru_hole circle
			(at -4.499864 71.000112 270)
			(size 1.016 1.016)
			(drill 0.7112)
			(layers "*.Cu" "*.Mask")
			(remove_unused_layers no)
			(net "GND")
			(clearance 0.1016)
			(thermal_gap 0.1016)
		)
		(pad "B71" thru_hole circle
			(at -2.499868 72.00011 270)
			(size 1.016 1.016)
			(drill 0.7112)
			(layers "*.Cu" "*.Mask")
			(remove_unused_layers no)
			(net "T8_BLAD3_RXD")
			(clearance 0.1016)
			(thermal_gap 0.1016)
		)
		(pad "B72" thru_hole circle
			(at -4.499864 73.000108 270)
			(size 1.016 1.016)
			(drill 0.7112)
			(layers "*.Cu" "*.Mask")
			(remove_unused_layers no)
			(net "T8_BLAD3_TXD")
			(clearance 0.1016)
			(thermal_gap 0.1016)
		)
	)
)
